(kicad_pcb
	(version 20260206)
	(generator "pcbnew")
	(generator_version "10.0")
	(general
		(thickness 1.6)
		(legacy_teardrops no)
	)
	(paper "A4")
	(title_block
		(title "fcb — 12433-1M.1206WZS1330.brd")
		(comment 1 "Open Vault / Knox (Wiwynn) / footprints 58-65 of 495")
	)
	(layers
		(0 "F.Cu" signal "TOP")
		(4 "In1.Cu" signal "L2GND")
		(6 "In2.Cu" signal "L3VCC")
		(2 "B.Cu" signal "BOTTOM")
		(9 "F.Adhes" user "F.Adhesive")
		(11 "B.Adhes" user "B.Adhesive")
		(13 "F.Paste" user "Package Geometry/Pastemask Top")
		(15 "B.Paste" user "Package Geometry/Pastemask Bottom")
		(5 "F.SilkS" user "Ref Des/Silkscreen Top")
		(7 "B.SilkS" user "Ref Des/Silkscreen Bottom")
		(1 "F.Mask" user "Board Geometry/Soldermask Top")
		(3 "B.Mask" user "Board Geometry/Soldermask Bottom")
		(17 "Dwgs.User" user "User.Drawings")
		(19 "Cmts.User" user "User.Comments")
		(21 "Eco1.User" user "User.Eco1")
		(23 "Eco2.User" user "User.Eco2")
		(25 "Edge.Cuts" user "Board Geometry/Outline")
		(27 "Margin" user)
		(31 "F.CrtYd" user "Package Geometry/Place Bound Top")
		(29 "B.CrtYd" user "Package Geometry/Place Bound Bottom")
		(35 "F.Fab" user "Ref Des/Assembly Top")
		(33 "B.Fab" user "Ref Des/Assembly Bottom")
	)
	(footprint ""
		(layer "F.Cu")
		(at 9.4488 -64.8208 180)
		(property "Reference" "R26"
			(at 0 0 180)
			(layer "F.SilkS")
			(hide yes)
			(effects
				(font
					(size 1.27 1.27)
				)
			)
		)
		(property "Value" "0R2J-2-GP"
			(at 0.064008 -3.993896 180)
			(unlocked yes)
			(layer "F.Fab")
			(hide yes)
			(effects
				(font
					(size 1.016 1.016)
					(thickness 0.1524)
				)
			)
		)
		(property "Device Type" "R402H16"
			(at 0.064008 -5.517896 180)
			(unlocked yes)
			(layer "F.Fab")
			(hide yes)
			(effects
				(font
					(size 1.016 1.016)
					(thickness 0.1524)
				)
			)
		)
		(duplicate_pad_numbers_are_jumpers no)
		(fp_line
			(start 0.508 -0.9398)
			(end -0.508 -0.9398)
			(stroke
				(width 0.1524)
				(type default)
			)
			(layer "F.SilkS")
		)
		(fp_line
			(start -0.508 -0.9398)
			(end -0.508 0.9398)
			(stroke
				(width 0.1524)
				(type default)
			)
			(layer "F.SilkS")
		)
		(fp_rect
			(start -0.508 0.9398)
			(end 0.508 -0.9398)
			(stroke
				(width 0)
				(type default)
			)
			(fill no)
			(layer "F.CrtYd")
		)
		(fp_rect
			(start -0.508 0.9398)
			(end 0.508 -0.9398)
			(stroke
				(width 0)
				(type default)
			)
			(fill no)
			(layer "F.Fab")
		)
		(pad "1" smd custom
			(at 0 -0.4445 180)
			(size 0.1397 0.1397)
			(layers "F.Cu" "F.Mask" "F.Paste")
			(net "LED_DR_LED5_K")
			(options
				(clearance outline)
				(anchor circle)
			)
			(primitives
				(gr_poly
					(pts
						(arc
							(start -0.1778 -0.2794)
							(mid -0.249642 -0.249642)
							(end -0.2794 -0.1778)
						)
						(arc
							(start -0.2794 0.1778)
							(mid -0.249642 0.249642)
							(end -0.1778 0.2794)
						)
						(arc
							(start 0.1778 0.2794)
							(mid 0.249642 0.249642)
							(end 0.2794 0.1778)
						)
						(arc
							(start 0.2794 -0.1778)
							(mid 0.249642 -0.249642)
							(end 0.1778 -0.2794)
						)
					)
					(width 0)
					(fill yes)
				)
			)
		)
		(pad "2" smd custom
			(at 0 0.4445 180)
			(size 0.1397 0.1397)
			(layers "F.Cu" "F.Mask" "F.Paste")
			(net "GND")
			(options
				(clearance outline)
				(anchor circle)
			)
			(primitives
				(gr_poly
					(pts
						(arc
							(start -0.1778 -0.2794)
							(mid -0.249642 -0.249642)
							(end -0.2794 -0.1778)
						)
						(arc
							(start -0.2794 0.1778)
							(mid -0.249642 0.249642)
							(end -0.1778 0.2794)
						)
						(arc
							(start 0.1778 0.2794)
							(mid 0.249642 0.249642)
							(end 0.2794 0.1778)
						)
						(arc
							(start 0.2794 -0.1778)
							(mid 0.249642 -0.249642)
							(end 0.1778 -0.2794)
						)
					)
					(width 0)
					(fill yes)
				)
			)
		)
	)
	(footprint ""
		(layer "F.Cu")
		(at 30.6832 -149.073616)
		(property "Reference" "R35"
			(at 0 0 0)
			(layer "F.SilkS")
			(hide yes)
			(effects
				(font
					(size 1.27 1.27)
				)
			)
		)
		(property "Value" "10KR2F-2-GP"
			(at 0.064008 -3.993896 0)
			(unlocked yes)
			(layer "F.Fab")
			(hide yes)
			(effects
				(font
					(size 1.016 1.016)
					(thickness 0.1524)
				)
			)
		)
		(property "Device Type" "R402H16"
			(at 0.064008 -5.517896 0)
			(unlocked yes)
			(layer "F.Fab")
			(hide yes)
			(effects
				(font
					(size 1.016 1.016)
					(thickness 0.1524)
				)
			)
		)
		(duplicate_pad_numbers_are_jumpers no)
		(fp_line
			(start -0.508 -0.9398)
			(end -0.508 0.9398)
			(stroke
				(width 0.1524)
				(type default)
			)
			(layer "F.SilkS")
		)
		(fp_line
			(start 0.508 -0.9398)
			(end -0.508 -0.9398)
			(stroke
				(width 0.1524)
				(type default)
			)
			(layer "F.SilkS")
		)
		(fp_rect
			(start -0.508 0.9398)
			(end 0.508 -0.9398)
			(stroke
				(width 0)
				(type default)
			)
			(fill no)
			(layer "F.CrtYd")
		)
		(fp_rect
			(start -0.508 0.9398)
			(end 0.508 -0.9398)
			(stroke
				(width 0)
				(type default)
			)
			(fill no)
			(layer "F.Fab")
		)
		(pad "1" smd custom
			(at 0 -0.4445)
			(size 0.1397 0.1397)
			(layers "F.Cu" "F.Mask" "F.Paste")
			(net "NCT7904_VSEN6")
			(options
				(clearance outline)
				(anchor circle)
			)
			(primitives
				(gr_poly
					(pts
						(arc
							(start -0.1778 -0.2794)
							(mid -0.249642 -0.249642)
							(end -0.2794 -0.1778)
						)
						(arc
							(start -0.2794 0.1778)
							(mid -0.249642 0.249642)
							(end -0.1778 0.2794)
						)
						(arc
							(start 0.1778 0.2794)
							(mid 0.249642 0.249642)
							(end 0.2794 0.1778)
						)
						(arc
							(start 0.2794 -0.1778)
							(mid 0.249642 -0.249642)
							(end 0.1778 -0.2794)
						)
					)
					(width 0)
					(fill yes)
				)
			)
		)
		(pad "2" smd custom
			(at 0 0.4445)
			(size 0.1397 0.1397)
			(layers "F.Cu" "F.Mask" "F.Paste")
			(net "GND")
			(options
				(clearance outline)
				(anchor circle)
			)
			(primitives
				(gr_poly
					(pts
						(arc
							(start -0.1778 -0.2794)
							(mid -0.249642 -0.249642)
							(end -0.2794 -0.1778)
						)
						(arc
							(start -0.2794 0.1778)
							(mid -0.249642 0.249642)
							(end -0.1778 0.2794)
						)
						(arc
							(start 0.1778 0.2794)
							(mid 0.249642 0.249642)
							(end 0.2794 0.1778)
						)
						(arc
							(start 0.2794 -0.1778)
							(mid 0.249642 -0.249642)
							(end 0.1778 -0.2794)
						)
					)
					(width 0)
					(fill yes)
				)
			)
		)
	)
	(footprint ""
		(layer "F.Cu")
		(at 41.3258 -136.271 90)
		(property "Reference" "PC88"
			(at 0 0 90)
			(layer "F.SilkS")
			(hide yes)
			(effects
				(font
					(size 1.27 1.27)
				)
			)
		)
		(property "Value" "SC220P50V2KX-3GP"
			(at 1.1811 -2.7051 90)
			(unlocked yes)
			(layer "F.Fab")
			(hide yes)
			(effects
				(font
					(size 1.016 1.016)
					(thickness 0.1524)
				)
			)
		)
		(property "Device Type" "C402H22"
			(at 1.1811 -4.2291 90)
			(unlocked yes)
			(layer "F.Fab")
			(hide yes)
			(effects
				(font
					(size 1.016 1.016)
					(thickness 0.1524)
				)
			)
		)
		(duplicate_pad_numbers_are_jumpers no)
		(fp_rect
			(start -0.4318 0.9525)
			(end 0.4318 -0.9525)
			(stroke
				(width 0)
				(type default)
			)
			(fill no)
			(layer "F.CrtYd")
		)
		(fp_rect
			(start -0.4318 0.9525)
			(end 0.4318 -0.9525)
			(stroke
				(width 0)
				(type default)
			)
			(fill no)
			(layer "F.Fab")
		)
		(pad "1" smd custom
			(at 0 -0.4445 90)
			(size 0.1524 0.1524)
			(layers "F.Cu" "F.Mask" "F.Paste")
			(net "P12VL_2490_SENSE")
			(options
				(clearance outline)
				(anchor circle)
			)
			(primitives
				(gr_poly
					(pts
						(arc
							(start 0.3048 -0.2032)
							(mid 0.275042 -0.275042)
							(end 0.2032 -0.3048)
						)
						(arc
							(start -0.2032 -0.3048)
							(mid -0.275042 -0.275042)
							(end -0.3048 -0.2032)
						)
						(arc
							(start -0.3048 0.2032)
							(mid -0.275042 0.275042)
							(end -0.2032 0.3048)
						)
						(arc
							(start 0.2032 0.3048)
							(mid 0.275042 0.275042)
							(end 0.3048 0.2032)
						)
					)
					(width 0)
					(fill yes)
				)
			)
		)
		(pad "2" smd custom
			(at 0 0.4445 90)
			(size 0.1524 0.1524)
			(layers "F.Cu" "F.Mask" "F.Paste")
			(net "P12VL_2490_VCC")
			(options
				(clearance outline)
				(anchor circle)
			)
			(primitives
				(gr_poly
					(pts
						(arc
							(start 0.3048 -0.2032)
							(mid 0.275042 -0.275042)
							(end 0.2032 -0.3048)
						)
						(arc
							(start -0.2032 -0.3048)
							(mid -0.275042 -0.275042)
							(end -0.3048 -0.2032)
						)
						(arc
							(start -0.3048 0.2032)
							(mid -0.275042 0.275042)
							(end -0.2032 0.3048)
						)
						(arc
							(start 0.2032 0.3048)
							(mid 0.275042 0.275042)
							(end 0.3048 0.2032)
						)
					)
					(width 0)
					(fill yes)
				)
			)
		)
	)
	(footprint ""
		(layer "F.Cu")
		(at 23.241 -361.188)
		(property "Reference" "PR5"
			(at 0 0 0)
			(layer "F.SilkS")
			(hide yes)
			(effects
				(font
					(size 1.27 1.27)
				)
			)
		)
		(property "Value" "0R2J-2-GP"
			(at 0.064008 -3.993896 0)
			(unlocked yes)
			(layer "F.Fab")
			(hide yes)
			(effects
				(font
					(size 1.016 1.016)
					(thickness 0.1524)
				)
			)
		)
		(property "Device Type" "R402H16"
			(at 0.064008 -5.517896 0)
			(unlocked yes)
			(layer "F.Fab")
			(hide yes)
			(effects
				(font
					(size 1.016 1.016)
					(thickness 0.1524)
				)
			)
		)
		(duplicate_pad_numbers_are_jumpers no)
		(fp_line
			(start -0.508 -0.9398)
			(end -0.508 0.9398)
			(stroke
				(width 0.1524)
				(type default)
			)
			(layer "F.SilkS")
		)
		(fp_line
			(start 0.508 -0.9398)
			(end -0.508 -0.9398)
			(stroke
				(width 0.1524)
				(type default)
			)
			(layer "F.SilkS")
		)
		(fp_rect
			(start -0.508 0.9398)
			(end 0.508 -0.9398)
			(stroke
				(width 0)
				(type default)
			)
			(fill no)
			(layer "F.CrtYd")
		)
		(fp_rect
			(start -0.508 0.9398)
			(end 0.508 -0.9398)
			(stroke
				(width 0)
				(type default)
			)
			(fill no)
			(layer "F.Fab")
		)
		(pad "1" smd custom
			(at 0 -0.4445)
			(size 0.1397 0.1397)
			(layers "F.Cu" "F.Mask" "F.Paste")
			(net "ADM1276_VCAP")
			(options
				(clearance outline)
				(anchor circle)
			)
			(primitives
				(gr_poly
					(pts
						(arc
							(start -0.1778 -0.2794)
							(mid -0.249642 -0.249642)
							(end -0.2794 -0.1778)
						)
						(arc
							(start -0.2794 0.1778)
							(mid -0.249642 0.249642)
							(end -0.1778 0.2794)
						)
						(arc
							(start 0.1778 0.2794)
							(mid 0.249642 0.249642)
							(end 0.2794 0.1778)
						)
						(arc
							(start 0.2794 -0.1778)
							(mid 0.249642 -0.249642)
							(end 0.1778 -0.2794)
						)
					)
					(width 0)
					(fill yes)
				)
			)
		)
		(pad "2" smd custom
			(at 0 0.4445)
			(size 0.1397 0.1397)
			(layers "F.Cu" "F.Mask" "F.Paste")
			(net "ADM1276_ADR")
			(options
				(clearance outline)
				(anchor circle)
			)
			(primitives
				(gr_poly
					(pts
						(arc
							(start -0.1778 -0.2794)
							(mid -0.249642 -0.249642)
							(end -0.2794 -0.1778)
						)
						(arc
							(start -0.2794 0.1778)
							(mid -0.249642 0.249642)
							(end -0.1778 0.2794)
						)
						(arc
							(start 0.1778 0.2794)
							(mid 0.249642 0.249642)
							(end 0.2794 0.1778)
						)
						(arc
							(start 0.2794 -0.1778)
							(mid 0.249642 -0.249642)
							(end 0.1778 -0.2794)
						)
					)
					(width 0)
					(fill yes)
				)
			)
		)
	)
	(footprint ""
		(layer "F.Cu")
		(at 41.4782 -177.6222)
		(property "Reference" "C253"
			(at 0 0 0)
			(layer "F.SilkS")
			(hide yes)
			(effects
				(font
					(size 1.27 1.27)
				)
			)
		)
		(property "Value" "SC4D7U6D3V3KX-GP"
			(at 0 -2.8194 0)
			(unlocked yes)
			(layer "F.Fab")
			(hide yes)
			(effects
				(font
					(size 1.016 1.016)
					(thickness 0.1524)
				)
			)
		)
		(property "Device Type" "C603H36"
			(at 0 -4.3434 0)
			(unlocked yes)
			(layer "F.Fab")
			(hide yes)
			(effects
				(font
					(size 1.016 1.016)
					(thickness 0.1524)
				)
			)
		)
		(duplicate_pad_numbers_are_jumpers no)
		(fp_line
			(start 0.508 0)
			(end -0.508 0)
			(stroke
				(width 0.2032)
				(type default)
			)
			(layer "F.SilkS")
		)
		(fp_rect
			(start -0.5842 1.3335)
			(end 0.5842 -1.3335)
			(stroke
				(width 0)
				(type default)
			)
			(fill no)
			(layer "F.CrtYd")
		)
		(fp_rect
			(start -0.5842 1.3335)
			(end 0.5842 -1.3335)
			(stroke
				(width 0)
				(type default)
			)
			(fill no)
			(layer "F.Fab")
		)
		(pad "1" smd custom
			(at 0 -0.762)
			(size 0.2159 0.2159)
			(layers "F.Cu" "F.Mask" "F.Paste")
			(net "D_LATCH_PRE#")
			(options
				(clearance outline)
				(anchor circle)
			)
			(primitives
				(gr_poly
					(pts
						(arc
							(start -0.3302 -0.4318)
							(mid -0.402042 -0.402042)
							(end -0.4318 -0.3302)
						)
						(arc
							(start -0.4318 0.3302)
							(mid -0.402042 0.402042)
							(end -0.3302 0.4318)
						)
						(arc
							(start 0.3302 0.4318)
							(mid 0.402042 0.402042)
							(end 0.4318 0.3302)
						)
						(arc
							(start 0.4318 -0.3302)
							(mid 0.402042 -0.402042)
							(end 0.3302 -0.4318)
						)
					)
					(width 0)
					(fill yes)
				)
			)
		)
		(pad "2" smd custom
			(at 0 0.762)
			(size 0.2159 0.2159)
			(layers "F.Cu" "F.Mask" "F.Paste")
			(net "GND")
			(options
				(clearance outline)
				(anchor circle)
			)
			(primitives
				(gr_poly
					(pts
						(arc
							(start -0.3302 -0.4318)
							(mid -0.402042 -0.402042)
							(end -0.4318 -0.3302)
						)
						(arc
							(start -0.4318 0.3302)
							(mid -0.402042 0.402042)
							(end -0.3302 0.4318)
						)
						(arc
							(start 0.3302 0.4318)
							(mid 0.402042 0.402042)
							(end 0.4318 0.3302)
						)
						(arc
							(start 0.4318 -0.3302)
							(mid 0.402042 -0.402042)
							(end 0.3302 -0.4318)
						)
					)
					(width 0)
					(fill yes)
				)
			)
		)
	)
	(footprint ""
		(layer "F.Cu")
		(at 37.719 -373.9896 180)
		(property "Reference" "PR25"
			(at 0 0 180)
			(layer "F.SilkS")
			(hide yes)
			(effects
				(font
					(size 1.27 1.27)
				)
			)
		)
		(property "Value" "0R2J-2-GP"
			(at 0.064008 -3.993896 180)
			(unlocked yes)
			(layer "F.Fab")
			(hide yes)
			(effects
				(font
					(size 1.016 1.016)
					(thickness 0.1524)
				)
			)
		)
		(property "Device Type" "R402H16"
			(at 0.064008 -5.517896 180)
			(unlocked yes)
			(layer "F.Fab")
			(hide yes)
			(effects
				(font
					(size 1.016 1.016)
					(thickness 0.1524)
				)
			)
		)
		(duplicate_pad_numbers_are_jumpers no)
		(fp_line
			(start 0.508 -0.9398)
			(end -0.508 -0.9398)
			(stroke
				(width 0.1524)
				(type default)
			)
			(layer "F.SilkS")
		)
		(fp_line
			(start -0.508 -0.9398)
			(end -0.508 0.9398)
			(stroke
				(width 0.1524)
				(type default)
			)
			(layer "F.SilkS")
		)
		(fp_rect
			(start -0.508 0.9398)
			(end 0.508 -0.9398)
			(stroke
				(width 0)
				(type default)
			)
			(fill no)
			(layer "F.CrtYd")
		)
		(fp_rect
			(start -0.508 0.9398)
			(end 0.508 -0.9398)
			(stroke
				(width 0)
				(type default)
			)
			(fill no)
			(layer "F.Fab")
		)
		(pad "1" smd custom
			(at 0 -0.4445 180)
			(size 0.1397 0.1397)
			(layers "F.Cu" "F.Mask" "F.Paste")
			(net "P12V")
			(options
				(clearance outline)
				(anchor circle)
			)
			(primitives
				(gr_poly
					(pts
						(arc
							(start -0.1778 -0.2794)
							(mid -0.249642 -0.249642)
							(end -0.2794 -0.1778)
						)
						(arc
							(start -0.2794 0.1778)
							(mid -0.249642 0.249642)
							(end -0.1778 0.2794)
						)
						(arc
							(start 0.1778 0.2794)
							(mid 0.249642 0.249642)
							(end 0.2794 0.1778)
						)
						(arc
							(start 0.2794 -0.1778)
							(mid 0.249642 -0.249642)
							(end 0.1778 -0.2794)
						)
					)
					(width 0)
					(fill yes)
				)
			)
		)
		(pad "2" smd custom
			(at 0 0.4445 180)
			(size 0.1397 0.1397)
			(layers "F.Cu" "F.Mask" "F.Paste")
			(net "ADM1276_GATE_RSV")
			(options
				(clearance outline)
				(anchor circle)
			)
			(primitives
				(gr_poly
					(pts
						(arc
							(start -0.1778 -0.2794)
							(mid -0.249642 -0.249642)
							(end -0.2794 -0.1778)
						)
						(arc
							(start -0.2794 0.1778)
							(mid -0.249642 0.249642)
							(end -0.1778 0.2794)
						)
						(arc
							(start 0.1778 0.2794)
							(mid 0.249642 0.249642)
							(end 0.2794 0.1778)
						)
						(arc
							(start 0.2794 -0.1778)
							(mid 0.249642 -0.249642)
							(end 0.1778 -0.2794)
						)
					)
					(width 0)
					(fill yes)
				)
			)
		)
	)
	(footprint ""
		(layer "F.Cu")
		(at 22.86 -122.555)
		(property "Reference" "PR61"
			(at 0 0 0)
			(layer "F.SilkS")
			(hide yes)
			(effects
				(font
					(size 1.27 1.27)
				)
			)
		)
		(property "Value" "D002R2512F-GP"
			(at -3.228594 -1.194054 0)
			(unlocked yes)
			(layer "F.Fab")
			(hide yes)
			(effects
				(font
					(size 1.016 1.016)
					(thickness 0.1524)
				)
			)
		)
		(property "Device Type" "R2512-2H32"
			(at -3.228594 -2.718054 0)
			(unlocked yes)
			(layer "F.Fab")
			(hide yes)
			(effects
				(font
					(size 1.016 1.016)
					(thickness 0.1524)
				)
			)
		)
		(duplicate_pad_numbers_are_jumpers no)
		(fp_line
			(start -1.9685 -3.81)
			(end 1.9685 -3.81)
			(stroke
				(width 0.1524)
				(type default)
			)
			(layer "F.SilkS")
		)
		(fp_line
			(start -1.9685 3.81)
			(end -1.9685 -3.81)
			(stroke
				(width 0.1524)
				(type default)
			)
			(layer "F.SilkS")
		)
		(fp_line
			(start 1.9685 -3.81)
			(end 1.9685 3.81)
			(stroke
				(width 0.1524)
				(type default)
			)
			(layer "F.SilkS")
		)
		(fp_line
			(start 1.9685 3.81)
			(end -1.9685 3.81)
			(stroke
				(width 0.1524)
				(type default)
			)
			(layer "F.SilkS")
		)
		(fp_rect
			(start -1.5875 3.175)
			(end 1.5875 -3.175)
			(stroke
				(width 0)
				(type default)
			)
			(fill no)
			(layer "F.CrtYd")
		)
		(fp_poly
			(pts
				(xy -2.2225 3.8862) (xy -2.2225 0.00254) (xy -1.5875 0.00254) (xy -1.5875 3.175) (xy 1.5875 3.175)
				(xy 1.5875 -3.175) (xy -1.5875 -3.175) (xy -1.5875 -0.00254) (xy -2.2225 -0.00254) (xy -2.2225 -3.8862)
				(xy 2.2225 -3.8862) (xy 2.2225 3.8862)
			)
			(stroke
				(width 0)
				(type default)
			)
			(fill no)
			(layer "F.CrtYd")
		)
		(fp_rect
			(start -2.2225 3.8862)
			(end 2.2225 -3.8862)
			(stroke
				(width 0)
				(type default)
			)
			(fill no)
			(layer "F.Fab")
		)
		(pad "1" smd rect
			(at 0 -2.273808)
			(size 3.429 2.5654)
			(layers "F.Cu" "F.Mask" "F.Paste")
			(net "P12V")
		)
		(pad "2" smd rect
			(at 0 2.273808)
			(size 3.429 2.5654)
			(layers "F.Cu" "F.Mask" "F.Paste")
			(net "P12VU_NET")
		)
	)
	(footprint ""
		(layer "F.Cu")
		(at 22.71649 -162.262566 180)
		(property "Reference" "R8"
			(at 0 0 180)
			(layer "F.SilkS")
			(hide yes)
			(effects
				(font
					(size 1.27 1.27)
				)
			)
		)
		(property "Value" "0R5J-5-GP"
			(at 0 -8.9535 180)
			(unlocked yes)
			(layer "F.Fab")
			(hide yes)
			(effects
				(font
					(size 1.27 1.016)
					(thickness 0.1524)
				)
			)
		)
		(property "Device Type" "R805H24"
			(at 0 -10.6299 180)
			(unlocked yes)
			(layer "F.Fab")
			(hide yes)
			(effects
				(font
					(size 1.27 1.016)
					(thickness 0.1524)
				)
			)
		)
		(duplicate_pad_numbers_are_jumpers no)
		(fp_line
			(start 0.889 1.7018)
			(end 0.889 -0.508)
			(stroke
				(width 0.1524)
				(type default)
			)
			(layer "F.SilkS")
		)
		(fp_line
			(start 0.889 -1.7018)
			(end 0.889 -0.381)
			(stroke
				(width 0.1524)
				(type default)
			)
			(layer "F.SilkS")
		)
		(fp_line
			(start 0.889 -1.7018)
			(end -0.889 -1.7018)
			(stroke
				(width 0.1524)
				(type default)
			)
			(layer "F.SilkS")
		)
		(fp_line
			(start -0.889 1.7018)
			(end 0.889 1.7018)
			(stroke
				(width 0.1524)
				(type default)
			)
			(layer "F.SilkS")
		)
		(fp_line
			(start -0.889 0.0762)
			(end -0.889 1.7018)
			(stroke
				(width 0.1524)
				(type default)
			)
			(layer "F.SilkS")
		)
		(fp_line
			(start -0.889 -1.7018)
			(end -0.889 0.2794)
			(stroke
				(width 0.1524)
				(type default)
			)
			(layer "F.SilkS")
		)
		(fp_poly
			(pts
				(xy 0.9652 -1.778) (xy 0.9652 1.778) (xy -0.9652 1.778) (xy -0.9652 -1.778)
			)
			(stroke
				(width 0)
				(type default)
			)
			(fill no)
			(layer "F.CrtYd")
		)
		(fp_rect
			(start -0.9652 1.778)
			(end 0.9652 -1.778)
			(stroke
				(width 0)
				(type default)
			)
			(fill no)
			(layer "F.Fab")
		)
		(pad "1" smd rect
			(at 0 -0.9652 180)
			(size 1.397 1.143)
			(layers "F.Cu" "F.Mask" "F.Paste")
			(net "NCT7904_GND")
		)
		(pad "2" smd rect
			(at 0 0.9652 180)
			(size 1.397 1.143)
			(layers "F.Cu" "F.Mask" "F.Paste")
			(net "GND")
		)
	)
)
